# S9S_MB_2U (Grand Teton) — schematic netlist excerpt (pin names and nets, part order shuffled) for the footprints in the layout excerpt that follows; sources: Cadence DE-HDL packaged netlist, KiCad conversion of 03242023_DA0F0TMBIJ0_F0T_Motherboard_J_brd_V01_OCP.brd

U216  APX80929SAG7  APX809-29SAG-7 IC  pkg SOT23_123XI  page 164
  GND  = GND
  RESET_L  = HP_OCP_V3_2_RST
  VCC  = P3V3_OCP_V3_2

C606  Q_CAP  1UF 25V 10% X6S  pkg C0402  page 202 : A = PGPPA_AUX ; B = GND
R4754  Q_RES  33.2 1% CHIP  pkg 0402LF  page 164 : A = HP_LVC3_OCP_V3_2_PWRGD_R ; B = HP_LVC3_OCP_V3_2_PWRGD_R2

(kicad_pcb
	(version 20260206)
	(generator "pcbnew")
	(generator_version "10.0")
	(general
		(thickness 1.6)
		(legacy_teardrops no)
	)
	(paper "A4")
	(title_block
		(title "03242023_DA0F0TMBIJ0_F0T_Motherboard_J_brd_V01_OCP.brd")
		(comment 1 "Grand Teton / footprints 1035-1037 of 6105")
	)
	(layers
		(0 "F.Cu" signal "TOP")
		(4 "In1.Cu" signal "GND")
		(6 "In2.Cu" signal "IN1")
		(8 "In3.Cu" signal "GND1")
		(10 "In4.Cu" signal "IN2")
		(12 "In5.Cu" signal "GND2")
		(14 "In6.Cu" signal "IN3")
		(16 "In7.Cu" signal "GND3")
		(18 "In8.Cu" signal "VCC")
		(20 "In9.Cu" signal "VCC1")
		(22 "In10.Cu" signal "GND4")
		(24 "In11.Cu" signal "IN4")
		(26 "In12.Cu" signal "GND5")
		(28 "In13.Cu" signal "IN5")
		(30 "In14.Cu" signal "GND6")
		(32 "In15.Cu" signal "IN6")
		(34 "In16.Cu" signal "GND7")
		(2 "B.Cu" signal "BOTTOM")
		(9 "F.Adhes" user "F.Adhesive")
		(11 "B.Adhes" user "B.Adhesive")
		(13 "F.Paste" user "Package Geometry/Pastemask Top")
		(15 "B.Paste" user "Package Geometry/Pastemask Bottom")
		(5 "F.SilkS" user "Ref Des/Silkscreen Top")
		(7 "B.SilkS" user "Ref Des/Silkscreen Bottom")
		(1 "F.Mask" user "Board Geometry/Soldermask Top")
		(3 "B.Mask" user "Board Geometry/Soldermask Bottom")
		(17 "Dwgs.User" user "User.Drawings")
		(19 "Cmts.User" user "User.Comments")
		(21 "Eco1.User" user "User.Eco1")
		(23 "Eco2.User" user "User.Eco2")
		(25 "Edge.Cuts" user "Board Geometry/Outline")
		(27 "Margin" user)
		(31 "F.CrtYd" user "Package Geometry/Place Bound Top")
		(29 "B.CrtYd" user "Package Geometry/Place Bound Bottom")
		(35 "F.Fab" user "Ref Des/Assembly Top")
		(33 "B.Fab" user "Ref Des/Assembly Bottom")
	)
	(footprint ""
		(layer "F.Cu")
		(at 136.3853 -114.38382)
		(property "Reference" "R4754"
			(at 0 0 0)
			(layer "F.SilkS")
			(hide yes)
			(effects
				(font
					(size 1.27 1.27)
				)
			)
		)
		(property "Value" ""
			(at 0 0 0)
			(layer "F.Fab")
			(effects
				(font
					(size 1.27 1.27)
				)
			)
		)
		(duplicate_pad_numbers_are_jumpers no)
		(fp_line
			(start -0.7874 -0.4064)
			(end 0.7874 -0.4064)
			(stroke
				(width 0.1524)
				(type default)
			)
			(layer "F.SilkS")
		)
		(fp_line
			(start -0.7874 0.4064)
			(end -0.7874 -0.4064)
			(stroke
				(width 0.1524)
				(type default)
			)
			(layer "F.SilkS")
		)
		(fp_line
			(start 0.7874 -0.4064)
			(end 0.7874 0.4064)
			(stroke
				(width 0.1524)
				(type default)
			)
			(layer "F.SilkS")
		)
		(fp_line
			(start 0.7874 0.4064)
			(end -0.7874 0.4064)
			(stroke
				(width 0.1524)
				(type default)
			)
			(layer "F.SilkS")
		)
		(fp_line
			(start -0.67945 -0.305054)
			(end -0.12065 -0.305054)
			(stroke
				(width 0.1)
				(type default)
			)
			(layer "F.Fab")
		)
		(fp_line
			(start -0.67945 0.3048)
			(end -0.67945 -0.305054)
			(stroke
				(width 0.1)
				(type default)
			)
			(layer "F.Fab")
		)
		(fp_line
			(start -0.12065 -0.305054)
			(end -0.12065 -0.2794)
			(stroke
				(width 0.1)
				(type default)
			)
			(layer "F.Fab")
		)
		(fp_line
			(start -0.12065 -0.2794)
			(end 0.12065 -0.2794)
			(stroke
				(width 0.1)
				(type default)
			)
			(layer "F.Fab")
		)
		(fp_line
			(start -0.12065 0.2794)
			(end -0.12065 0.3048)
			(stroke
				(width 0.1)
				(type default)
			)
			(layer "F.Fab")
		)
		(fp_line
			(start -0.12065 0.3048)
			(end -0.67945 0.3048)
			(stroke
				(width 0.1)
				(type default)
			)
			(layer "F.Fab")
		)
		(fp_line
			(start 0.120396 0.2794)
			(end -0.12065 0.2794)
			(stroke
				(width 0.1)
				(type default)
			)
			(layer "F.Fab")
		)
		(fp_line
			(start 0.120396 0.3048)
			(end 0.120396 0.2794)
			(stroke
				(width 0.1)
				(type default)
			)
			(layer "F.Fab")
		)
		(fp_line
			(start 0.12065 -0.3048)
			(end 0.67945 -0.3048)
			(stroke
				(width 0.1)
				(type default)
			)
			(layer "F.Fab")
		)
		(fp_line
			(start 0.12065 -0.2794)
			(end 0.12065 -0.3048)
			(stroke
				(width 0.1)
				(type default)
			)
			(layer "F.Fab")
		)
		(fp_line
			(start 0.67945 -0.3048)
			(end 0.67945 0.3048)
			(stroke
				(width 0.1)
				(type default)
			)
			(layer "F.Fab")
		)
		(fp_line
			(start 0.67945 0.3048)
			(end 0.120396 0.3048)
			(stroke
				(width 0.1)
				(type default)
			)
			(layer "F.Fab")
		)
		(pad "1" smd circle
			(at -0.40005 0)
			(size 0 0)
			(layers "F.Cu" "F.Mask" "F.Paste")
			(net "HP_LVC3_OCP_V3_2_PWRGD_R")
		)
		(pad "2" smd circle
			(at 0.40005 0)
			(size 0 0)
			(layers "F.Cu" "F.Mask" "F.Paste")
			(net "HP_LVC3_OCP_V3_2_PWRGD_R2")
		)
	)
	(footprint ""
		(layer "F.Cu")
		(at 80.46847 -38.693852 180)
		(property "Reference" "U216"
			(at 1.35636 -2.19202 0)
			(unlocked yes)
			(layer "F.SilkS")
			(effects
				(font
					(size 0.7874 0.5842)
					(thickness 0.1524)
				)
				(justify left)
			)
		)
		(property "Value" ""
			(at 0 0 180)
			(layer "F.Fab")
			(effects
				(font
					(size 1.27 1.27)
				)
			)
		)
		(duplicate_pad_numbers_are_jumpers no)
		(fp_line
			(start 1.759712 1.500124)
			(end -1.759712 1.500124)
			(stroke
				(width 0.1524)
				(type default)
			)
			(layer "F.SilkS")
		)
		(fp_line
			(start 1.759712 -1.500124)
			(end 1.759712 1.500124)
			(stroke
				(width 0.1524)
				(type default)
			)
			(layer "F.SilkS")
		)
		(fp_line
			(start -1.759712 1.500124)
			(end -1.759712 -1.500124)
			(stroke
				(width 0.1524)
				(type default)
			)
			(layer "F.SilkS")
		)
		(fp_line
			(start -1.759712 -1.500124)
			(end 1.759712 -1.500124)
			(stroke
				(width 0.1524)
				(type default)
			)
			(layer "F.SilkS")
		)
		(fp_line
			(start 0.700024 1.500124)
			(end -0.700024 1.500124)
			(stroke
				(width 0.1)
				(type default)
			)
			(layer "F.Fab")
		)
		(fp_line
			(start 0.700024 -1.500124)
			(end 0.700024 1.500124)
			(stroke
				(width 0.1)
				(type default)
			)
			(layer "F.Fab")
		)
		(fp_line
			(start -0.700024 1.500124)
			(end -0.700024 -1.500124)
			(stroke
				(width 0.1)
				(type default)
			)
			(layer "F.Fab")
		)
		(fp_line
			(start -0.700024 -1.500124)
			(end 0.700024 -1.500124)
			(stroke
				(width 0.1)
				(type default)
			)
			(layer "F.Fab")
		)
		(pad "1" smd rect
			(at -1.150112 -0.94996 90)
			(size 0.6604 0.9652)
			(layers "F.Cu" "F.Mask" "F.Paste")
			(net "GND")
		)
		(pad "2" smd rect
			(at -1.150112 0.94996 90)
			(size 0.6604 0.9652)
			(layers "F.Cu" "F.Mask" "F.Paste")
			(net "HP_OCP_V3_2_RST")
		)
		(pad "3" smd rect
			(at 1.150112 0 90)
			(size 0.6604 0.9652)
			(layers "F.Cu" "F.Mask" "F.Paste")
			(net "P3V3_OCP_V3_2")
		)
	)
	(footprint ""
		(layer "F.Cu")
		(at 333.155544 -18.797524 -90)
		(property "Reference" "C606"
			(at 0 0 270)
			(layer "F.SilkS")
			(hide yes)
			(effects
				(font
					(size 1.27 1.27)
				)
			)
		)
		(property "Value" ""
			(at 0 0 270)
			(layer "F.Fab")
			(effects
				(font
					(size 1.27 1.27)
				)
			)
		)
		(duplicate_pad_numbers_are_jumpers no)
		(fp_line
			(start -0.7874 0.4064)
			(end -0.7874 -0.4064)
			(stroke
				(width 0.1524)
				(type default)
			)
			(layer "F.SilkS")
		)
		(fp_line
			(start 0.7874 0.4064)
			(end -0.7874 0.4064)
			(stroke
				(width 0.1524)
				(type default)
			)
			(layer "F.SilkS")
		)
		(fp_line
			(start -0.7874 -0.4064)
			(end 0.7874 -0.4064)
			(stroke
				(width 0.1524)
				(type default)
			)
			(layer "F.SilkS")
		)
		(fp_line
			(start 0.7874 -0.4064)
			(end 0.7874 0.4064)
			(stroke
				(width 0.1524)
				(type default)
			)
			(layer "F.SilkS")
		)
		(fp_line
			(start -0.67945 0.3048)
			(end -0.67945 -0.305054)
			(stroke
				(width 0.1)
				(type default)
			)
			(layer "F.Fab")
		)
		(fp_line
			(start -0.12065 0.3048)
			(end -0.67945 0.3048)
			(stroke
				(width 0.1)
				(type default)
			)
			(layer "F.Fab")
		)
		(fp_line
			(start 0.120396 0.3048)
			(end 0.120396 0.2794)
			(stroke
				(width 0.1)
				(type default)
			)
			(layer "F.Fab")
		)
		(fp_line
			(start 0.67945 0.3048)
			(end 0.120396 0.3048)
			(stroke
				(width 0.1)
				(type default)
			)
			(layer "F.Fab")
		)
		(fp_line
			(start -0.12065 0.2794)
			(end -0.12065 0.3048)
			(stroke
				(width 0.1)
				(type default)
			)
			(layer "F.Fab")
		)
		(fp_line
			(start 0.120396 0.2794)
			(end -0.12065 0.2794)
			(stroke
				(width 0.1)
				(type default)
			)
			(layer "F.Fab")
		)
		(fp_line
			(start -0.12065 -0.2794)
			(end 0.12065 -0.2794)
			(stroke
				(width 0.1)
				(type default)
			)
			(layer "F.Fab")
		)
		(fp_line
			(start 0.12065 -0.2794)
			(end 0.12065 -0.3048)
			(stroke
				(width 0.1)
				(type default)
			)
			(layer "F.Fab")
		)
		(fp_line
			(start 0.12065 -0.3048)
			(end 0.67945 -0.3048)
			(stroke
				(width 0.1)
				(type default)
			)
			(layer "F.Fab")
		)
		(fp_line
			(start 0.67945 -0.3048)
			(end 0.67945 0.3048)
			(stroke
				(width 0.1)
				(type default)
			)
			(layer "F.Fab")
		)
		(fp_line
			(start -0.67945 -0.305054)
			(end -0.12065 -0.305054)
			(stroke
				(width 0.1)
				(type default)
			)
			(layer "F.Fab")
		)
		(fp_line
			(start -0.12065 -0.305054)
			(end -0.12065 -0.2794)
			(stroke
				(width 0.1)
				(type default)
			)
			(layer "F.Fab")
		)
		(pad "1" smd circle
			(at -0.40005 0 270)
			(size 0 0)
			(layers "F.Cu" "F.Mask" "F.Paste")
			(net "PGPPA_AUX")
		)
		(pad "2" smd circle
			(at 0.40005 0 270)
			(size 0 0)
			(layers "F.Cu" "F.Mask" "F.Paste")
			(net "GND")
		)
	)
)
